FILE_TYPE = CONNECTIVITY;
{Allegro Design Entry HDL 17.2-2016 S081 (4005846) 1/11/2022}
"PAGE_NUMBER" = 202;
0"NC";
1"VCC_PLD_CORE\g";
2"P3V3_AUX\g";
3"P3V3_AUX_FPGA_VCCIO0\g";
4"P3V3_AUX\g";
5"P3V3_AUX_FPGA_VCCIO1\g";
6"P3V3_AUX\g";
7"P3V3_AUX\g";
8"P3V3_AUX_FPGA_VCCIO2\g";
9"P3V3_AUX_FPGA_VCCIO5\g";
10"P3V3_AUX\g";
11"P3V3_AUX_FPGA_VCCIO3\g";
12"P3V3_AUX\g";
13"P3V3_AUX_FPGA_VCCIO4\g";
14"P3V3_AUX\g";
15"P3V3_AUX_FPGA_VCCIO1\g";
16"P3V3_AUX_FPGA_VCCIO5\g";
17"VCC_PLD_CORE\g";
18"P3V3_AUX_FPGA_VCCIO0\g";
19"P3V3_AUX_FPGA_VCCIO4\g";
20"P3V3_AUX_FPGA_VCCIO3\g";
21"P3V3_AUX_FPGA_VCCIO2\g";
22"GND\g";
23"GND\g";
24"GND\g";
25"GND\g";
26"GND\g";
27"GND\g";
28"GND\g";
29"GND\g";
%"LCMXO3LF9400C5BG484C"
"6","(-2975,1100)","0","pure_quanta","I1";
;
PART_NUMBER"AJ094000T08"
MATERIAL"IC"
PART_TYPE"SMLF"
VALUE"LCMXO3LF-9400C-5BG484C"
$LOCATION"U249"
CDS_LMAN_SYM_OUTLINE"-250,1350,250,-1350"
NEEDS_NO_SIZE"TRUE"
CDS_LIB"pure_quanta"
CDS_LOCATION"U249"
$SEC"6"
CDS_SEC"6";
"GND52"
$PN"AB22"29;
"GND51"
$PN"AB1"29;
"GND49"
$PN"Y7"29;
"GND50"
$PN"Y16"29;
"GND48"
$PN"W12"29;
"GND47"
$PN"V21"29;
"GND46"
$PN"V2"29;
"GND45"
$PN"R15"29;
"GND44"
$PN"R8"29;
"GND43"
$PN"P14"29;
"GND42"
$PN"P13"29;
"GND41"
$PN"P12"29;
"GND40"
$PN"P11"29;
"GND39"
$PN"P10"29;
"GND38"
$PN"P9"29;
"GND37"
$PN"N21"29;
"GND36"
$PN"N14"29;
"GND35"
$PN"N9"29;
"GND34"
$PN"M14"29;
"GND33"
$PN"M13"29;
"GND32"
$PN"M10"29;
"GND31"
$PN"M9"29;
"GND30"
$PN"M4"29;
"GND29"
$PN"L18"29;
"GND28"
$PN"L14"29;
"GND27"
$PN"L13"29;
"GND26"
$PN"L10"29;
"GND25"
$PN"L9"29;
"GND24"
$PN"L2"29;
"GND23"
$PN"K21"29;
"GND22"
$PN"K14"29;
"GND21"
$PN"K9"29;
"GND20"
$PN"J14"29;
"GND19"
$PN"J13"29;
"GND18"
$PN"J12"29;
"GND17"
$PN"J11"29;
"GND16"
$PN"J10"29;
"GND15"
$PN"J9"29;
"GND14"
$PN"H15"29;
"GND13"
$PN"H13"29;
"GND12"
$PN"H10"29;
"GND11"
$PN"H8"29;
"GND10"
$PN"F21"29;
"GND9"
$PN"F2"29;
"GND8"
$PN"E18"29;
"GND7"
$PN"E5"29;
"GND6"
$PN"C11"29;
"GND5"
$PN"C2"29;
"GND4"
$PN"B16"29;
"GND3"
$PN"B7"29;
"GND2"
$PN"A22"29;
"GND1"
$PN"A1"29;
%"UNIVERSAL_GND"
"1","(1500,825)","0","logical_power","I10";
;
CDS_LIB"logical_power"
HDL_POWER"GND"
ROOM"IO_SLOT";
"A"23;
%"Q_CAP"
"1","(-4500,-2125)","0","pure_quanta","I100";
;
PART_NUMBER"CH31006KB18"
PACK_TYPE"C0402"
MATERIAL"X7R"
TOLERANCE"10%"
VOLTAGE"50V"
VALUE"0.01UF"
$LOCATION"C1124"
CDS_LIB"pure_quanta"
CDS_LOCATION"C1124"
$SEC"1"
CDS_SEC"1";
"B"
$PN"2"26;
"A"
$PN"1"11;
%"Q_CAP"
"1","(-4800,-2125)","0","pure_quanta","I101";
;
PART_NUMBER"CH4104K1B00"
PACK_TYPE"0402"
MATERIAL"X7R"
TOLERANCE"10%"
VALUE"0.1UF"
VOLTAGE"25V"
$LOCATION"C1941"
CDS_LIB"pure_quanta"
CDS_LOCATION"C1941"
$SEC"1"
CDS_SEC"1";
"B"
$PN"2"26;
"A"
$PN"1"11;
%"LCMXO3LF9400C5BG484C"
"5","(-4950,1400)","0","pure_quanta","I102";
;
PART_NUMBER"AJ094000T08"
PART_TYPE"SMLF"
MATERIAL"IC"
VALUE"LCMXO3LF-9400C-5BG484C"
$LOCATION"U249"
CDS_LIB"pure_quanta"
NEEDS_NO_SIZE"TRUE"
CDS_LMAN_SYM_OUTLINE"-400,1000,400,-1000"
CDS_LOCATION"U249"
$SEC"5"
CDS_SEC"5";
"VCCIO0_5"
$PN"G13"18;
"VCCIO0_6"
$PN"H9"18;
"VCCIO0_9"
$PN"H14"18;
"VCCIO0_8"
$PN"H12"18;
"VCCIO0_7"
$PN"H11"18;
"VCCIO0_4"
$PN"G10"18;
"VCCIO0_3"
$PN"C16"18;
"VCCIO0_2"
$PN"C12"18;
"VCCIO0_1"
$PN"C7"18;
"VCCIO1_9"
$PN"V20"15;
"VCCIO1_8"
$PN"P15"15;
"VCCIO1_7"
$PN"N15"15;
"VCCIO1_6"
$PN"M18"15;
"VCCIO1_5"
$PN"M15"15;
"VCCIO1_4"
$PN"L15"15;
"VCCIO1_3"
$PN"K15"15;
"VCCIO1_2"
$PN"J15"15;
"VCCIO1_1"
$PN"F20"15;
"VCCIO2_9"
$PN"W16"21;
"VCCIO2_8"
$PN"W11"21;
"VCCIO2_7"
$PN"W7"21;
"VCCIO2_6"
$PN"R14"21;
"VCCIO2_5"
$PN"R13"21;
"VCCIO2_4"
$PN"R12"21;
"VCCIO2_3"
$PN"R11"21;
"VCCIO2_2"
$PN"R10"21;
"VCCIO2_1"
$PN"R9"21;
"VCCIO3_3"
$PN"V3"20;
"VCCIO3_2"
$PN"P8"20;
"VCCIO3_1"
$PN"N8"20;
"VCCIO4_3"
$PN"M3"19;
"VCCIO4_2"
$PN"M8"19;
"VCCIO4_1"
$PN"L8"19;
"VCCIO5_3"
$PN"K8"16;
"VCCIO5_2"
$PN"J8"16;
"VCCIO5_1"
$PN"F3"16;
"VCC12"
$PN"N13"17;
"VCC11"
$PN"N12"17;
"VCC10"
$PN"N11"17;
"VCC9"
$PN"N10"17;
"VCC8"
$PN"M12"17;
"VCC7"
$PN"M11"17;
"VCC6"
$PN"L12"17;
"VCC5"
$PN"L11"17;
"VCC4"
$PN"K13"17;
"VCC3"
$PN"K12"17;
"VCC2"
$PN"K11"17;
"VCC1"
$PN"K10"17;
%"UNIVERSAL_POWER"
"1","(-6150,1725)","0","logical_power","I103";
;
HDL_POWER"P3V3_AUX_FPGA_VCCIO5"
CDS_LIB"logical_power";
"A"16;
%"UNIVERSAL_POWER"
"1","(-6150,1525)","0","logical_power","I104";
;
HDL_POWER"P3V3_AUX_FPGA_VCCIO4"
CDS_LIB"logical_power";
"A"19;
%"UNIVERSAL_POWER"
"1","(-6150,1225)","0","logical_power","I105";
;
HDL_POWER"P3V3_AUX_FPGA_VCCIO3"
CDS_LIB"logical_power";
"A"20;
%"UNIVERSAL_POWER"
"1","(-6150,1025)","0","logical_power","I106";
;
HDL_POWER"P3V3_AUX_FPGA_VCCIO2"
CDS_LIB"logical_power";
"A"21;
%"Q_CAP"
"1","(-5150,-2100)","0","pure_quanta","I107";
;
PART_NUMBER"CH6101MEB01"
VALUE"10UF"
PACK_TYPE"C0402"
MATERIAL"X6S"
TOLERANCE"20%"
VOLTAGE"6.3V"
$LOCATION"C1842"
CDS_LIB"pure_quanta"
CDS_LOCATION"C1842"
$SEC"1"
CDS_SEC"1";
"B"
$PN"2"26;
"A"
$PN"1"11;
%"Q_RES"
"1","(-5525,-1925)","0","pure_quanta","I108";
;
PART_NUMBER"CS-1003F900"
MATERIAL"CHIP"
TOLERANCE"1%"
WATTAGE"1/10W"
PACK_TYPE"0603LF"
VALUE"1"
$LOCATION"R3344"
CDS_LIB"pure_quanta"
CDS_LOCATION"R3344"
$SEC"1"
CDS_SEC"1";
"B"
$PN"2"11;
"A"
$PN"1"10;
%"UNIVERSAL_POWER"
"1","(-5950,-1775)","0","logical_power","I109";
;
HDL_POWER"P3V3_AUX"
CDS_LIB"logical_power";
"A"10;
%"UNIVERSAL_POWER"
"1","(1425,500)","0","logical_power","I11";
;
HDL_POWER"P3V3_AUX_FPGA_VCCIO1"
CDS_LIB"logical_power";
"A"5;
%"Q_RES"
"1","(-1700,2575)","0","pure_quanta","I119";
;
PART_NUMBER"CS-1003F900"
VALUE"1"
TOLERANCE"1%"
PACK_TYPE"0603LF"
WATTAGE"1/10W"
MATERIAL"CHIP"
$LOCATION"R3458"
CDS_LIB"pure_quanta"
CDS_LOCATION"R3458"
$SEC"1"
CDS_SEC"1";
"B"
$PN"2"1;
"A"
$PN"1"2;
%"Q_CAP"
"1","(1425,125)","0","pure_quanta","I12";
;
PART_NUMBER"CH31006KB18"
PACK_TYPE"C0402"
VOLTAGE"50V"
MATERIAL"X7R"
TOLERANCE"10%"
VALUE"0.01UF"
$LOCATION"C1933"
CDS_LIB"pure_quanta"
CDS_LOCATION"C1933"
$SEC"1"
CDS_SEC"1";
"B"
$PN"2"24;
"A"
$PN"1"5;
%"Q_CAP"
"1","(1700,2375)","0","pure_quanta","I120";
;
PART_NUMBER"CH31006KB18"
PACK_TYPE"C0402"
MATERIAL"X7R"
TOLERANCE"10%"
VOLTAGE"50V"
VALUE"0.01UF"
$LOCATION"C1934"
CDS_LIB"pure_quanta"
CDS_LOCATION"C1934"
$SEC"1"
CDS_SEC"1";
"B"
$PN"2"22;
"A"
$PN"1"1;
%"Q_CAP"
"1","(1450,2375)","0","pure_quanta","I121";
;
PART_NUMBER"CH4104K1B00"
PACK_TYPE"0402"
TOLERANCE"10%"
VOLTAGE"25V"
MATERIAL"X7R"
VALUE"0.1UF"
$LOCATION"C1150"
CDS_LIB"pure_quanta"
CDS_LOCATION"C1150"
$SEC"1"
CDS_SEC"1";
"B"
$PN"2"22;
"A"
$PN"1"1;
%"UNIVERSAL_GND"
"1","(1425,-200)","0","logical_power","I13";
;
CDS_LIB"logical_power"
HDL_POWER"GND"
ROOM"IO_SLOT";
"A"24;
%"UNIVERSAL_POWER"
"1","(1450,-625)","0","logical_power","I14";
;
HDL_POWER"P3V3_AUX_FPGA_VCCIO2"
CDS_LIB"logical_power";
"A"8;
%"Q_CAP"
"1","(1450,-1000)","0","pure_quanta","I15";
;
PART_NUMBER"CH31006KB18"
VALUE"0.01UF"
VOLTAGE"50V"
PACK_TYPE"C0402"
MATERIAL"X7R"
TOLERANCE"10%"
$LOCATION"C1146"
CDS_LIB"pure_quanta"
CDS_LOCATION"C1146"
$SEC"1"
CDS_SEC"1";
"B"
$PN"2"25;
"A"
$PN"1"8;
%"UNIVERSAL_GND"
"1","(1450,-1325)","0","logical_power","I16";
;
CDS_LIB"logical_power"
HDL_POWER"GND"
ROOM"IO_SLOT";
"A"25;
%"UNIVERSAL_POWER"
"1","(1750,-1875)","0","logical_power","I17";
;
HDL_POWER"P3V3_AUX_FPGA_VCCIO5"
CDS_LIB"logical_power";
"A"9;
%"Q_CAP"
"1","(1750,-2225)","0","pure_quanta","I18";
;
PART_NUMBER"CH31006KB18"
TOLERANCE"10%"
VALUE"0.01UF"
VOLTAGE"50V"
PACK_TYPE"C0402"
MATERIAL"X7R"
$LOCATION"C1904"
CDS_LIB"pure_quanta"
CDS_LOCATION"C1904"
$SEC"1"
CDS_SEC"1";
"B"
$PN"2"28;
"A"
$PN"1"9;
%"UNIVERSAL_GND"
"1","(1750,-2550)","0","logical_power","I19";
;
CDS_LIB"logical_power"
HDL_POWER"GND"
ROOM"IO_SLOT";
"A"28;
%"UNIVERSAL_POWER"
"1","(2200,2675)","0","logical_power","I2";
;
HDL_POWER"VCC_PLD_CORE"
CDS_LIB"logical_power";
"A"1;
%"Q_CAP"
"1","(1500,-2225)","0","pure_quanta","I20";
;
PART_NUMBER"CH31006KB18"
MATERIAL"X7R"
TOLERANCE"10%"
VOLTAGE"50V"
VALUE"0.01UF"
PACK_TYPE"C0402"
$LOCATION"C1898"
CDS_LIB"pure_quanta"
CDS_LOCATION"C1898"
$SEC"1"
CDS_SEC"1";
"B"
$PN"2"28;
"A"
$PN"1"9;
%"Q_CAP"
"1","(1200,2375)","0","pure_quanta","I21";
;
PART_NUMBER"CH31006KB18"
PACK_TYPE"C0402"
VOLTAGE"50V"
MATERIAL"X7R"
TOLERANCE"10%"
VALUE"0.01UF"
$LOCATION"C1931"
CDS_LIB"pure_quanta"
CDS_LOCATION"C1931"
$SEC"1"
CDS_SEC"1";
"B"
$PN"2"22;
"A"
$PN"1"1;
%"Q_CAP"
"1","(950,2375)","0","pure_quanta","I22";
;
PART_NUMBER"CH31006KB18"
MATERIAL"X7R"
PACK_TYPE"C0402"
TOLERANCE"10%"
VOLTAGE"50V"
VALUE"0.01UF"
$LOCATION"C1928"
CDS_LIB"pure_quanta"
CDS_LOCATION"C1928"
$SEC"1"
CDS_SEC"1";
"B"
$PN"2"22;
"A"
$PN"1"1;
%"Q_CAP"
"1","(700,2375)","0","pure_quanta","I23";
;
PART_NUMBER"CH31006KB18"
VOLTAGE"50V"
TOLERANCE"10%"
PACK_TYPE"C0402"
MATERIAL"X7R"
VALUE"0.01UF"
$LOCATION"C1919"
CDS_LIB"pure_quanta"
CDS_LOCATION"C1919"
$SEC"1"
CDS_SEC"1";
"B"
$PN"2"22;
"A"
$PN"1"1;
%"Q_CAP"
"1","(450,2375)","0","pure_quanta","I24";
;
PART_NUMBER"CH31006KB18"
VALUE"0.01UF"
PACK_TYPE"C0402"
MATERIAL"X7R"
TOLERANCE"10%"
VOLTAGE"50V"
$LOCATION"C1916"
CDS_LIB"pure_quanta"
CDS_LOCATION"C1916"
$SEC"1"
CDS_SEC"1";
"B"
$PN"2"22;
"A"
$PN"1"1;
%"Q_CAP"
"1","(200,2375)","0","pure_quanta","I25";
;
PART_NUMBER"CH4104K1B00"
PACK_TYPE"0402"
MATERIAL"X7R"
VOLTAGE"25V"
TOLERANCE"10%"
VALUE"0.1UF"
$LOCATION"C1907"
CDS_LIB"pure_quanta"
CDS_LOCATION"C1907"
$SEC"1"
CDS_SEC"1";
"B"
$PN"2"22;
"A"
$PN"1"1;
%"Q_CAP"
"1","(-50,2375)","0","pure_quanta","I26";
;
PART_NUMBER"CH31006KB18"
TOLERANCE"10%"
MATERIAL"X7R"
VOLTAGE"50V"
VALUE"0.01UF"
PACK_TYPE"C0402"
$LOCATION"C1903"
CDS_LIB"pure_quanta"
CDS_LOCATION"C1903"
$SEC"1"
CDS_SEC"1";
"B"
$PN"2"22;
"A"
$PN"1"1;
%"Q_CAP"
"1","(-300,2375)","0","pure_quanta","I27";
;
PART_NUMBER"CH31006KB18"
PACK_TYPE"C0402"
MATERIAL"X7R"
VOLTAGE"50V"
VALUE"0.01UF"
TOLERANCE"10%"
$LOCATION"C1897"
CDS_LIB"pure_quanta"
CDS_LOCATION"C1897"
$SEC"1"
CDS_SEC"1";
"B"
$PN"2"22;
"A"
$PN"1"1;
%"Q_CAP"
"1","(-575,2400)","0","pure_quanta","I28";
;
PART_NUMBER"CH31006KB18"
PACK_TYPE"C0402"
MATERIAL"X7R"
TOLERANCE"10%"
VOLTAGE"50V"
VALUE"0.01UF"
$LOCATION"C1912"
CDS_LIB"pure_quanta"
CDS_LOCATION"C1912"
$SEC"1"
CDS_SEC"1";
"B"
$PN"2"22;
"A"
$PN"1"1;
%"Q_CAP"
"1","(-925,2400)","0","pure_quanta","I29";
;
PART_NUMBER"CH4104K1B00"
PACK_TYPE"0402"
VALUE"0.1UF"
VOLTAGE"25V"
TOLERANCE"10%"
MATERIAL"X7R"
$LOCATION"C1943"
CDS_LIB"pure_quanta"
CDS_LOCATION"C1943"
$SEC"1"
CDS_SEC"1";
"B"
$PN"2"22;
"A"
$PN"1"1;
%"Q_CAP"
"1","(2200,2375)","0","pure_quanta","I3";
;
PART_NUMBER"CH31006KB18"
PACK_TYPE"C0402"
VOLTAGE"50V"
TOLERANCE"10%"
MATERIAL"X7R"
VALUE"0.01UF"
$LOCATION"C1154"
CDS_LIB"pure_quanta"
CDS_LOCATION"C1154"
$SEC"1"
CDS_SEC"1";
"B"
$PN"2"22;
"A"
$PN"1"1;
%"Q_CAP"
"1","(-1275,2400)","0","pure_quanta","I30";
;
PART_NUMBER"CH6101MEB01"
MATERIAL"X6S"
TOLERANCE"20%"
VOLTAGE"6.3V"
VALUE"10UF"
PACK_TYPE"C0402"
$LOCATION"C1936"
CDS_LIB"pure_quanta"
CDS_LOCATION"C1936"
$SEC"1"
CDS_SEC"1";
"B"
$PN"2"22;
"A"
$PN"1"1;
%"UNIVERSAL_POWER"
"1","(-2050,2875)","0","logical_power","I32";
;
HDL_POWER"P3V3_AUX"
CDS_LIB"logical_power";
"A"2;
%"Q_CAP"
"1","(1250,1150)","0","pure_quanta","I33";
;
PART_NUMBER"CH31006KB18"
VALUE"0.01UF"
TOLERANCE"10%"
MATERIAL"X7R"
VOLTAGE"50V"
PACK_TYPE"C0402"
$LOCATION"C1929"
CDS_LIB"pure_quanta"
CDS_LOCATION"C1929"
$SEC"1"
CDS_SEC"1";
"B"
$PN"2"23;
"A"
$PN"1"3;
%"Q_CAP"
"1","(1000,1150)","0","pure_quanta","I34";
;
PART_NUMBER"CH31006KB18"
VALUE"0.01UF"
TOLERANCE"10%"
MATERIAL"X7R"
VOLTAGE"50V"
PACK_TYPE"C0402"
$LOCATION"C1926"
CDS_LIB"pure_quanta"
CDS_LOCATION"C1926"
$SEC"1"
CDS_SEC"1";
"B"
$PN"2"23;
"A"
$PN"1"3;
%"Q_CAP"
"1","(750,1150)","0","pure_quanta","I35";
;
PART_NUMBER"CH31006KB18"
VOLTAGE"50V"
MATERIAL"X7R"
TOLERANCE"10%"
PACK_TYPE"C0402"
VALUE"0.01UF"
$LOCATION"C1917"
CDS_LIB"pure_quanta"
CDS_LOCATION"C1917"
$SEC"1"
CDS_SEC"1";
"B"
$PN"2"23;
"A"
$PN"1"3;
%"Q_CAP"
"1","(500,1150)","0","pure_quanta","I36";
;
PART_NUMBER"CH31006KB18"
VALUE"0.01UF"
VOLTAGE"50V"
TOLERANCE"10%"
MATERIAL"X7R"
PACK_TYPE"C0402"
$LOCATION"C1914"
CDS_LIB"pure_quanta"
CDS_LOCATION"C1914"
$SEC"1"
CDS_SEC"1";
"B"
$PN"2"23;
"A"
$PN"1"3;
%"Q_CAP"
"1","(1175,125)","0","pure_quanta","I37";
;
PART_NUMBER"CH31006KB18"
MATERIAL"X7R"
PACK_TYPE"C0402"
VOLTAGE"50V"
TOLERANCE"10%"
VALUE"0.01UF"
$LOCATION"C1930"
CDS_LIB"pure_quanta"
CDS_LOCATION"C1930"
$SEC"1"
CDS_SEC"1";
"B"
$PN"2"24;
"A"
$PN"1"5;
%"Q_CAP"
"1","(925,125)","0","pure_quanta","I38";
;
PART_NUMBER"CH31006KB18"
VOLTAGE"50V"
PACK_TYPE"C0402"
MATERIAL"X7R"
TOLERANCE"10%"
VALUE"0.01UF"
$LOCATION"C1927"
CDS_LIB"pure_quanta"
CDS_LOCATION"C1927"
$SEC"1"
CDS_SEC"1";
"B"
$PN"2"24;
"A"
$PN"1"5;
%"Q_CAP"
"1","(675,125)","0","pure_quanta","I39";
;
PART_NUMBER"CH31006KB18"
MATERIAL"X7R"
VALUE"0.01UF"
PACK_TYPE"C0402"
VOLTAGE"50V"
TOLERANCE"10%"
$LOCATION"C1918"
CDS_LIB"pure_quanta"
CDS_LOCATION"C1918"
$SEC"1"
CDS_SEC"1";
"B"
$PN"2"24;
"A"
$PN"1"5;
%"UNIVERSAL_GND"
"1","(2200,2025)","0","logical_power","I4";
;
CDS_LIB"logical_power"
HDL_POWER"GND"
ROOM"IO_SLOT";
"A"22;
%"Q_CAP"
"1","(425,125)","0","pure_quanta","I40";
;
PART_NUMBER"CH31006KB18"
PACK_TYPE"C0402"
VOLTAGE"50V"
MATERIAL"X7R"
TOLERANCE"10%"
VALUE"0.01UF"
$LOCATION"C1915"
CDS_LIB"pure_quanta"
CDS_LOCATION"C1915"
$SEC"1"
CDS_SEC"1";
"B"
$PN"2"24;
"A"
$PN"1"5;
%"Q_CAP"
"1","(250,1150)","0","pure_quanta","I41";
;
PART_NUMBER"CH4104K1B00"
VOLTAGE"25V"
VALUE"0.1UF"
MATERIAL"X7R"
PACK_TYPE"0402"
TOLERANCE"10%"
$LOCATION"C1905"
CDS_LIB"pure_quanta"
CDS_LOCATION"C1905"
$SEC"1"
CDS_SEC"1";
"B"
$PN"2"23;
"A"
$PN"1"3;
%"Q_CAP"
"1","(0,1150)","0","pure_quanta","I42";
;
PART_NUMBER"CH31006KB18"
VALUE"0.01UF"
TOLERANCE"10%"
MATERIAL"X7R"
VOLTAGE"50V"
PACK_TYPE"C0402"
$LOCATION"C1901"
CDS_LIB"pure_quanta"
CDS_LOCATION"C1901"
$SEC"1"
CDS_SEC"1";
"B"
$PN"2"23;
"A"
$PN"1"3;
%"Q_CAP"
"1","(-250,1150)","0","pure_quanta","I43";
;
PART_NUMBER"CH31006KB18"
TOLERANCE"10%"
PACK_TYPE"C0402"
VALUE"0.01UF"
VOLTAGE"50V"
MATERIAL"X7R"
$LOCATION"C1895"
CDS_LIB"pure_quanta"
CDS_LOCATION"C1895"
$SEC"1"
CDS_SEC"1";
"B"
$PN"2"23;
"A"
$PN"1"3;
%"Q_CAP"
"1","(-525,1150)","0","pure_quanta","I44";
;
PART_NUMBER"CH31006KB18"
VALUE"0.01UF"
TOLERANCE"10%"
MATERIAL"X7R"
VOLTAGE"50V"
PACK_TYPE"C0402"
$LOCATION"C1910"
CDS_LIB"pure_quanta"
CDS_LOCATION"C1910"
$SEC"1"
CDS_SEC"1";
"B"
$PN"2"23;
"A"
$PN"1"3;
%"Q_CAP"
"1","(175,125)","0","pure_quanta","I45";
;
PART_NUMBER"CH4104K1B00"
MATERIAL"X7R"
TOLERANCE"10%"
VOLTAGE"25V"
PACK_TYPE"0402"
VALUE"0.1UF"
$LOCATION"C1906"
CDS_LIB"pure_quanta"
CDS_LOCATION"C1906"
$SEC"1"
CDS_SEC"1";
"B"
$PN"2"24;
"A"
$PN"1"5;
%"Q_CAP"
"1","(-75,125)","0","pure_quanta","I46";
;
PART_NUMBER"CH31006KB18"
PACK_TYPE"C0402"
VOLTAGE"50V"
MATERIAL"X7R"
TOLERANCE"10%"
VALUE"0.01UF"
$LOCATION"C1902"
CDS_LIB"pure_quanta"
CDS_LOCATION"C1902"
$SEC"1"
CDS_SEC"1";
"B"
$PN"2"24;
"A"
$PN"1"5;
%"Q_CAP"
"1","(-325,125)","0","pure_quanta","I47";
;
PART_NUMBER"CH31006KB18"
PACK_TYPE"C0402"
VALUE"0.01UF"
VOLTAGE"50V"
TOLERANCE"10%"
MATERIAL"X7R"
$LOCATION"C1896"
CDS_LIB"pure_quanta"
CDS_LOCATION"C1896"
$SEC"1"
CDS_SEC"1";
"B"
$PN"2"24;
"A"
$PN"1"5;
%"Q_CAP"
"1","(-600,125)","0","pure_quanta","I48";
;
PART_NUMBER"CH31006KB18"
MATERIAL"X7R"
VOLTAGE"50V"
VALUE"0.01UF"
TOLERANCE"10%"
PACK_TYPE"C0402"
$LOCATION"C1911"
CDS_LIB"pure_quanta"
CDS_LOCATION"C1911"
$SEC"1"
CDS_SEC"1";
"B"
$PN"2"24;
"A"
$PN"1"5;
%"Q_CAP"
"1","(1200,-1000)","0","pure_quanta","I49";
;
PART_NUMBER"CH31006KB18"
VALUE"0.01UF"
TOLERANCE"10%"
MATERIAL"X7R"
PACK_TYPE"C0402"
VOLTAGE"50V"
$LOCATION"C1142"
CDS_LIB"pure_quanta"
CDS_LOCATION"C1142"
$SEC"1"
CDS_SEC"1";
"B"
$PN"2"25;
"A"
$PN"1"8;
%"Q_CAP"
"1","(1950,2375)","0","pure_quanta","I5";
;
PART_NUMBER"CH31006KB18"
PACK_TYPE"C0402"
MATERIAL"X7R"
TOLERANCE"10%"
VOLTAGE"50V"
VALUE"0.01UF"
$LOCATION"C1152"
CDS_LIB"pure_quanta"
CDS_LOCATION"C1152"
$SEC"1"
CDS_SEC"1";
"B"
$PN"2"22;
"A"
$PN"1"1;
%"Q_CAP"
"1","(950,-1000)","0","pure_quanta","I50";
;
PART_NUMBER"CH31006KB18"
PACK_TYPE"C0402"
VOLTAGE"50V"
MATERIAL"X7R"
TOLERANCE"10%"
VALUE"0.01UF"
$LOCATION"C1138"
CDS_LIB"pure_quanta"
CDS_LOCATION"C1138"
$SEC"1"
CDS_SEC"1";
"B"
$PN"2"25;
"A"
$PN"1"8;
%"Q_CAP"
"1","(700,-1000)","0","pure_quanta","I51";
;
PART_NUMBER"CH31006KB18"
TOLERANCE"10%"
PACK_TYPE"C0402"
VOLTAGE"50V"
MATERIAL"X7R"
VALUE"0.01UF"
$LOCATION"C1133"
CDS_LIB"pure_quanta"
CDS_LOCATION"C1133"
$SEC"1"
CDS_SEC"1";
"B"
$PN"2"25;
"A"
$PN"1"8;
%"Q_CAP"
"1","(450,-1000)","0","pure_quanta","I52";
;
PART_NUMBER"CH31006KB18"
TOLERANCE"10%"
MATERIAL"X7R"
PACK_TYPE"C0402"
VOLTAGE"50V"
VALUE"0.01UF"
$LOCATION"C1127"
CDS_LIB"pure_quanta"
CDS_LOCATION"C1127"
$SEC"1"
CDS_SEC"1";
"B"
$PN"2"25;
"A"
$PN"1"8;
%"Q_CAP"
"1","(1225,-2225)","0","pure_quanta","I53";
;
PART_NUMBER"CH31006KB18"
MATERIAL"X7R"
VALUE"0.01UF"
VOLTAGE"50V"
PACK_TYPE"C0402"
TOLERANCE"10%"
$LOCATION"C1913"
CDS_LIB"pure_quanta"
CDS_LOCATION"C1913"
$SEC"1"
CDS_SEC"1";
"B"
$PN"2"28;
"A"
$PN"1"9;
%"Q_CAP"
"1","(925,-2225)","0","pure_quanta","I54";
;
PART_NUMBER"CH4104K1B00"
TOLERANCE"10%"
MATERIAL"X7R"
VALUE"0.1UF"
VOLTAGE"25V"
PACK_TYPE"0402"
$LOCATION"C1947"
CDS_LIB"pure_quanta"
CDS_LOCATION"C1947"
$SEC"1"
CDS_SEC"1";
"B"
$PN"2"28;
"A"
$PN"1"9;
%"Q_CAP"
"1","(575,-2200)","0","pure_quanta","I55";
;
PART_NUMBER"CH6101MEB01"
MATERIAL"X6S"
TOLERANCE"20%"
PACK_TYPE"C0402"
VALUE"10UF"
VOLTAGE"6.3V"
$LOCATION"C1940"
CDS_LIB"pure_quanta"
CDS_LOCATION"C1940"
$SEC"1"
CDS_SEC"1";
"B"
$PN"2"28;
"A"
$PN"1"9;
%"Q_CAP"
"1","(200,-1000)","0","pure_quanta","I56";
;
PART_NUMBER"CH4104K1B00"
PACK_TYPE"0402"
MATERIAL"X7R"
TOLERANCE"10%"
VALUE"0.1UF"
VOLTAGE"25V"
$LOCATION"C1122"
CDS_LIB"pure_quanta"
CDS_LOCATION"C1122"
$SEC"1"
CDS_SEC"1";
"B"
$PN"2"25;
"A"
$PN"1"8;
%"Q_CAP"
"1","(-50,-1000)","0","pure_quanta","I57";
;
PART_NUMBER"CH31006KB18"
MATERIAL"X7R"
VOLTAGE"50V"
TOLERANCE"10%"
PACK_TYPE"C0402"
VALUE"0.01UF"
$LOCATION"C1900"
CDS_LIB"pure_quanta"
CDS_LOCATION"C1900"
$SEC"1"
CDS_SEC"1";
"B"
$PN"2"25;
"A"
$PN"1"8;
%"Q_CAP"
"1","(-300,-1000)","0","pure_quanta","I58";
;
PART_NUMBER"CH31006KB18"
VOLTAGE"50V"
PACK_TYPE"C0402"
TOLERANCE"10%"
VALUE"0.01UF"
MATERIAL"X7R"
$LOCATION"C1894"
CDS_LIB"pure_quanta"
CDS_LOCATION"C1894"
$SEC"1"
CDS_SEC"1";
"B"
$PN"2"25;
"A"
$PN"1"8;
%"Q_CAP"
"1","(-575,-1000)","0","pure_quanta","I59";
;
PART_NUMBER"CH31006KB18"
MATERIAL"X7R"
PACK_TYPE"C0402"
VALUE"0.01UF"
VOLTAGE"50V"
TOLERANCE"10%"
$LOCATION"C1909"
CDS_LIB"pure_quanta"
CDS_LOCATION"C1909"
$SEC"1"
CDS_SEC"1";
"B"
$PN"2"25;
"A"
$PN"1"8;
%"Q_RES"
"1","(200,-2025)","0","pure_quanta","I60";
;
PART_NUMBER"CS-1003F900"
MATERIAL"CHIP"
WATTAGE"1/10W"
VALUE"1"
TOLERANCE"1%"
PACK_TYPE"0603LF"
$LOCATION"R3349"
CDS_LIB"pure_quanta"
CDS_LOCATION"R3349"
$SEC"1"
CDS_SEC"1";
"B"
$PN"2"9;
"A"
$PN"1"14;
%"UNIVERSAL_POWER"
"1","(-225,-1875)","0","logical_power","I61";
;
HDL_POWER"P3V3_AUX"
CDS_LIB"logical_power";
"A"14;
%"Q_CAP"
"1","(-825,1150)","0","pure_quanta","I62";
;
PART_NUMBER"CH4104K1B00"
PACK_TYPE"0402"
MATERIAL"X7R"
VOLTAGE"25V"
VALUE"0.1UF"
TOLERANCE"10%"
$LOCATION"C1945"
CDS_LIB"pure_quanta"
CDS_LOCATION"C1945"
$SEC"1"
CDS_SEC"1";
"B"
$PN"2"23;
"A"
$PN"1"3;
%"Q_RES"
"1","(-1475,1350)","0","pure_quanta","I63";
;
PART_NUMBER"CS-1003F900"
PACK_TYPE"0603LF"
MATERIAL"CHIP"
WATTAGE"1/10W"
TOLERANCE"1%"
VALUE"1"
$LOCATION"R3346"
CDS_LIB"pure_quanta"
CDS_LOCATION"R3346"
$SEC"1"
CDS_SEC"1";
"B"
$PN"2"3;
"A"
$PN"1"4;
%"Q_CAP"
"1","(-1175,1175)","0","pure_quanta","I64";
;
PART_NUMBER"CH6101MEB01"
PACK_TYPE"C0402"
MATERIAL"X6S"
VOLTAGE"6.3V"
TOLERANCE"20%"
VALUE"10UF"
$LOCATION"C1938"
CDS_LIB"pure_quanta"
CDS_LOCATION"C1938"
$SEC"1"
CDS_SEC"1";
"B"
$PN"2"23;
"A"
$PN"1"3;
%"Q_CAP"
"1","(-900,125)","0","pure_quanta","I65";
;
PART_NUMBER"CH4104K1B00"
PACK_TYPE"0402"
MATERIAL"X7R"
VOLTAGE"25V"
VALUE"0.1UF"
TOLERANCE"10%"
$LOCATION"C1946"
CDS_LIB"pure_quanta"
CDS_LOCATION"C1946"
$SEC"1"
CDS_SEC"1";
"B"
$PN"2"24;
"A"
$PN"1"5;
%"Q_CAP"
"1","(-1250,150)","0","pure_quanta","I66";
;
PART_NUMBER"CH6101MEB01"
MATERIAL"X6S"
PACK_TYPE"C0402"
TOLERANCE"20%"
VALUE"10UF"
VOLTAGE"6.3V"
$LOCATION"C1939"
CDS_LIB"pure_quanta"
CDS_LOCATION"C1939"
$SEC"1"
CDS_SEC"1";
"B"
$PN"2"24;
"A"
$PN"1"5;
%"Q_RES"
"1","(-1475,325)","0","pure_quanta","I67";
;
PART_NUMBER"CS-1003F900"
WATTAGE"1/10W"
PACK_TYPE"0603LF"
MATERIAL"CHIP"
TOLERANCE"1%"
VALUE"1"
$LOCATION"R3348"
CDS_LIB"pure_quanta"
CDS_LOCATION"R3348"
$SEC"1"
CDS_SEC"1";
"B"
$PN"2"5;
"A"
$PN"1"6;
%"UNIVERSAL_POWER"
"1","(-1900,1500)","0","logical_power","I68";
;
HDL_POWER"P3V3_AUX"
CDS_LIB"logical_power";
"A"4;
%"UNIVERSAL_POWER"
"1","(-1900,475)","0","logical_power","I69";
;
HDL_POWER"P3V3_AUX"
CDS_LIB"logical_power";
"A"6;
%"Q_CAP"
"1","(-875,-1000)","0","pure_quanta","I70";
;
PART_NUMBER"CH4104K1B00"
VALUE"0.1UF"
VOLTAGE"25V"
TOLERANCE"10%"
PACK_TYPE"0402"
MATERIAL"X7R"
$LOCATION"C1944"
CDS_LIB"pure_quanta"
CDS_LOCATION"C1944"
$SEC"1"
CDS_SEC"1";
"B"
$PN"2"25;
"A"
$PN"1"8;
%"Q_CAP"
"1","(-1225,-975)","0","pure_quanta","I71";
;
PART_NUMBER"CH6101MEB01"
MATERIAL"X6S"
TOLERANCE"20%"
VOLTAGE"6.3V"
VALUE"10UF"
PACK_TYPE"C0402"
$LOCATION"C1937"
CDS_LIB"pure_quanta"
CDS_LOCATION"C1937"
$SEC"1"
CDS_SEC"1";
"B"
$PN"2"25;
"A"
$PN"1"8;
%"Q_RES"
"1","(-1450,-800)","0","pure_quanta","I72";
;
PART_NUMBER"CS-1003F900"
TOLERANCE"1%"
PACK_TYPE"0603LF"
WATTAGE"1/10W"
VALUE"1"
MATERIAL"CHIP"
$LOCATION"R3347"
CDS_LIB"pure_quanta"
CDS_LOCATION"R3347"
$SEC"1"
CDS_SEC"1";
"B"
$PN"2"8;
"A"
$PN"1"7;
%"UNIVERSAL_POWER"
"1","(-1225,-1850)","0","logical_power","I73";
;
HDL_POWER"P3V3_AUX_FPGA_VCCIO4"
CDS_LIB"logical_power";
"A"13;
%"Q_CAP"
"1","(-1225,-2175)","0","pure_quanta","I74";
;
PART_NUMBER"CH31006KB18"
TOLERANCE"10%"
VOLTAGE"50V"
MATERIAL"X7R"
VALUE"0.01UF"
PACK_TYPE"C0402"
$LOCATION"C1899"
CDS_LIB"pure_quanta"
CDS_LOCATION"C1899"
$SEC"1"
CDS_SEC"1";
"B"
$PN"2"27;
"A"
$PN"1"13;
%"UNIVERSAL_GND"
"1","(-1225,-2500)","0","logical_power","I75";
;
CDS_LIB"logical_power"
HDL_POWER"GND"
ROOM"IO_SLOT";
"A"27;
%"Q_CAP"
"1","(-1475,-2175)","0","pure_quanta","I76";
;
PART_NUMBER"CH31006KB18"
MATERIAL"X7R"
TOLERANCE"10%"
VOLTAGE"50V"
VALUE"0.01UF"
PACK_TYPE"C0402"
$LOCATION"C1893"
CDS_LIB"pure_quanta"
CDS_LOCATION"C1893"
$SEC"1"
CDS_SEC"1";
"B"
$PN"2"27;
"A"
$PN"1"13;
%"Q_CAP"
"1","(-1750,-2175)","0","pure_quanta","I77";
;
PART_NUMBER"CH31006KB18"
VOLTAGE"50V"
PACK_TYPE"C0402"
TOLERANCE"10%"
VALUE"0.01UF"
MATERIAL"X7R"
$LOCATION"C1908"
CDS_LIB"pure_quanta"
CDS_LOCATION"C1908"
$SEC"1"
CDS_SEC"1";
"B"
$PN"2"27;
"A"
$PN"1"13;
%"UNIVERSAL_POWER"
"1","(-1875,-650)","0","logical_power","I78";
;
HDL_POWER"P3V3_AUX"
CDS_LIB"logical_power";
"A"7;
%"UNIVERSAL_GND"
"1","(-2400,-350)","0","logical_power","I79";
;
CDS_LIB"logical_power"
HDL_POWER"GND"
ROOM"IO_SLOT";
"A"29;
%"UNIVERSAL_POWER"
"1","(1500,1475)","0","logical_power","I8";
;
HDL_POWER"P3V3_AUX_FPGA_VCCIO0"
CDS_LIB"logical_power";
"A"3;
%"Q_CAP"
"1","(-2050,-2175)","0","pure_quanta","I80";
;
PART_NUMBER"CH4104K1B00"
VALUE"0.1UF"
VOLTAGE"25V"
TOLERANCE"10%"
MATERIAL"X7R"
PACK_TYPE"0402"
$LOCATION"C1942"
CDS_LIB"pure_quanta"
CDS_LOCATION"C1942"
$SEC"1"
CDS_SEC"1";
"B"
$PN"2"27;
"A"
$PN"1"13;
%"Q_RES"
"1","(-2575,-1975)","0","pure_quanta","I81";
;
PART_NUMBER"CS-1003F900"
WATTAGE"1/10W"
VALUE"1"
MATERIAL"CHIP"
TOLERANCE"1%"
PACK_TYPE"0603LF"
$LOCATION"R3345"
CDS_LIB"pure_quanta"
CDS_LOCATION"R3345"
$SEC"1"
CDS_SEC"1";
"B"
$PN"2"13;
"A"
$PN"1"12;
%"Q_CAP"
"1","(-2400,-2150)","0","pure_quanta","I82";
;
PART_NUMBER"CH6101MEB01"
VOLTAGE"6.3V"
PACK_TYPE"C0402"
TOLERANCE"20%"
MATERIAL"X6S"
VALUE"10UF"
$LOCATION"C1935"
CDS_LIB"pure_quanta"
CDS_LOCATION"C1935"
$SEC"1"
CDS_SEC"1";
"B"
$PN"2"27;
"A"
$PN"1"13;
%"Q_CAP"
"1","(1500,1150)","0","pure_quanta","I9";
;
PART_NUMBER"CH31006KB18"
TOLERANCE"10%"
MATERIAL"X7R"
VOLTAGE"50V"
PACK_TYPE"C0402"
VALUE"0.01UF"
$LOCATION"C1932"
CDS_LIB"pure_quanta"
CDS_LOCATION"C1932"
$SEC"1"
CDS_SEC"1";
"B"
$PN"2"23;
"A"
$PN"1"3;
%"UNIVERSAL_POWER"
"1","(-6175,2425)","0","logical_power","I92";
;
HDL_POWER"VCC_PLD_CORE"
CDS_LIB"logical_power";
"A"17;
%"UNIVERSAL_POWER"
"1","(-3975,1725)","0","logical_power","I93";
;
HDL_POWER"P3V3_AUX_FPGA_VCCIO1"
CDS_LIB"logical_power";
"A"15;
%"UNIVERSAL_POWER"
"1","(-3975,1050)","0","logical_power","I94";
;
HDL_POWER"P3V3_AUX_FPGA_VCCIO0"
CDS_LIB"logical_power";
"A"18;
%"UNIVERSAL_POWER"
"1","(-3000,-1825)","0","logical_power","I95";
;
HDL_POWER"P3V3_AUX"
CDS_LIB"logical_power";
"A"12;
%"UNIVERSAL_POWER"
"1","(-3975,-1750)","0","logical_power","I96";
;
HDL_POWER"P3V3_AUX_FPGA_VCCIO3"
CDS_LIB"logical_power";
"A"11;
%"Q_CAP"
"1","(-3975,-2125)","0","pure_quanta","I97";
;
PART_NUMBER"CH31006KB18"
MATERIAL"X7R"
VALUE"0.01UF"
PACK_TYPE"C0402"
TOLERANCE"10%"
VOLTAGE"50V"
$LOCATION"C1118"
CDS_LIB"pure_quanta"
CDS_LOCATION"C1118"
$SEC"1"
CDS_SEC"1";
"B"
$PN"2"26;
"A"
$PN"1"11;
%"UNIVERSAL_GND"
"1","(-3975,-2450)","0","logical_power","I98";
;
CDS_LIB"logical_power"
HDL_POWER"GND"
ROOM"IO_SLOT";
"A"26;
%"Q_CAP"
"1","(-4225,-2125)","0","pure_quanta","I99";
;
PART_NUMBER"CH31006KB18"
VOLTAGE"50V"
VALUE"0.01UF"
TOLERANCE"10%"
MATERIAL"X7R"
PACK_TYPE"C0402"
$LOCATION"C1113"
CDS_LIB"pure_quanta"
CDS_LOCATION"C1113"
$SEC"1"
CDS_SEC"1";
"B"
$PN"2"26;
"A"
$PN"1"11;
END.
